(kicad_pcb
	(version 20260206)
	(generator "pcbnew")
	(generator_version "10.0")
	(general
		(thickness 1.6)
		(legacy_teardrops no)
	)
	(paper "A4")
	(title_block
		(title "01162023_DA0F0TEBIF0_F0T_Expander_BD_F_brd_V02_OCP.brd")
		(comment 1 "Grand Teton / footprint 6602 of 9728 (PEX1), pads 1424-1536 of 2397")
	)
	(layers
		(0 "F.Cu" signal "TOP")
		(4 "In1.Cu" signal "GND")
		(6 "In2.Cu" signal "VCC")
		(8 "In3.Cu" signal "VCC1")
		(10 "In4.Cu" signal "GND1")
		(12 "In5.Cu" signal "IN1")
		(14 "In6.Cu" signal "GND2")
		(16 "In7.Cu" signal "IN2")
		(18 "In8.Cu" signal "GND3")
		(20 "In9.Cu" signal "IN3")
		(22 "In10.Cu" signal "GND4")
		(24 "In11.Cu" signal "IN4")
		(26 "In12.Cu" signal "GND5")
		(28 "In13.Cu" signal "IN5")
		(30 "In14.Cu" signal "GND6")
		(32 "In15.Cu" signal "IN6")
		(34 "In16.Cu" signal "GND7")
		(2 "B.Cu" signal "BOTTOM")
		(9 "F.Adhes" user "F.Adhesive")
		(11 "B.Adhes" user "B.Adhesive")
		(13 "F.Paste" user "Package Geometry/Pastemask Top")
		(15 "B.Paste" user "Package Geometry/Pastemask Bottom")
		(5 "F.SilkS" user "Ref Des/Silkscreen Top")
		(7 "B.SilkS" user "Ref Des/Silkscreen Bottom")
		(1 "F.Mask" user "Board Geometry/Soldermask Top")
		(3 "B.Mask" user "Board Geometry/Soldermask Bottom")
		(17 "Dwgs.User" user "User.Drawings")
		(19 "Cmts.User" user "User.Comments")
		(21 "Eco1.User" user "User.Eco1")
		(23 "Eco2.User" user "User.Eco2")
		(25 "Edge.Cuts" user "Board Geometry/Outline")
		(27 "Margin" user)
		(31 "F.CrtYd" user "Package Geometry/Place Bound Top")
		(29 "B.CrtYd" user "Package Geometry/Place Bound Bottom")
		(35 "F.Fab" user "Ref Des/Assembly Top")
		(33 "B.Fab" user "Ref Des/Assembly Bottom")
	)
	(footprint ""
		(layer "F.Cu")
		(at 175.749966 -295.89984)
		(property "Reference" "PEX1"
			(at -3.353562 35.593274 0)
			(unlocked yes)
			(layer "F.SilkS")
			(effects
				(font
					(size 2.032 1.524)
					(thickness 0.1524)
				)
				(justify left)
			)
		)
		(property "Value" ""
			(at 0 0 0)
			(layer "F.Fab")
			(effects
				(font
					(size 1.27 1.27)
				)
			)
		)
		(duplicate_pad_numbers_are_jumpers no)
		(pad "BH5" smd circle
			(at -18.999962 21.850096)
			(size 0.4572 0.4572)
			(layers "F.Cu" "F.Mask" "F.Paste")
			(net "Net_1719")
		)
		(pad "BH6" smd circle
			(at -18.050002 21.850096)
			(size 0.4572 0.4572)
			(layers "F.Cu" "F.Mask" "F.Paste")
			(net "GND")
		)
		(pad "BH7" smd circle
			(at -17.100042 21.850096)
			(size 0.4572 0.4572)
			(layers "F.Cu" "F.Mask" "F.Paste")
			(net "Net_1717")
		)
		(pad "BH8" smd circle
			(at -16.150082 21.850096)
			(size 0.4572 0.4572)
			(layers "F.Cu" "F.Mask" "F.Paste")
			(net "GND")
		)
		(pad "BH9" smd circle
			(at -15.200122 21.850096)
			(size 0.4572 0.4572)
			(layers "F.Cu" "F.Mask" "F.Paste")
			(net "P5E_PEX1_STN2_RX_DP<47>")
		)
		(pad "BH10" smd circle
			(at -14.249908 21.850096)
			(size 0.4572 0.4572)
			(layers "F.Cu" "F.Mask" "F.Paste")
			(net "GND")
		)
		(pad "BH11" smd circle
			(at -13.299948 21.850096)
			(size 0.4572 0.4572)
			(layers "F.Cu" "F.Mask" "F.Paste")
			(net "P5E_PEX1_STN2_RX_DP<45>")
		)
		(pad "BH12" smd circle
			(at -12.349988 21.850096)
			(size 0.4572 0.4572)
			(layers "F.Cu" "F.Mask" "F.Paste")
			(net "GND")
		)
		(pad "BH13" smd circle
			(at -11.400028 21.850096)
			(size 0.4572 0.4572)
			(layers "F.Cu" "F.Mask" "F.Paste")
			(net "P5E_PEX1_STN2_RX_DP<43>")
		)
		(pad "BH14" smd circle
			(at -10.450068 21.850096)
			(size 0.4572 0.4572)
			(layers "F.Cu" "F.Mask" "F.Paste")
			(net "GND")
		)
		(pad "BH15" smd circle
			(at -9.500108 21.850096)
			(size 0.4572 0.4572)
			(layers "F.Cu" "F.Mask" "F.Paste")
			(net "P5E_PEX1_STN2_RX_DP<41>")
		)
		(pad "BH16" smd circle
			(at -8.549894 21.850096)
			(size 0.4572 0.4572)
			(layers "F.Cu" "F.Mask" "F.Paste")
			(net "GND")
		)
		(pad "BH17" smd circle
			(at -7.599934 21.850096)
			(size 0.4572 0.4572)
			(layers "F.Cu" "F.Mask" "F.Paste")
			(net "P5E_PEX1_STN2_RX_DP<39>")
		)
		(pad "BH18" smd circle
			(at -6.649974 21.850096)
			(size 0.4572 0.4572)
			(layers "F.Cu" "F.Mask" "F.Paste")
			(net "GND")
		)
		(pad "BH19" smd circle
			(at -5.700014 21.850096)
			(size 0.4572 0.4572)
			(layers "F.Cu" "F.Mask" "F.Paste")
			(net "P5E_PEX1_STN2_RX_DP<37>")
		)
		(pad "BH20" smd circle
			(at -4.750054 21.850096)
			(size 0.4572 0.4572)
			(layers "F.Cu" "F.Mask" "F.Paste")
			(net "GND")
		)
		(pad "BH21" smd circle
			(at -3.800094 21.850096)
			(size 0.4572 0.4572)
			(layers "F.Cu" "F.Mask" "F.Paste")
			(net "P5E_PEX1_STN2_RX_DP<35>")
		)
		(pad "BH22" smd circle
			(at -2.84988 21.850096)
			(size 0.4572 0.4572)
			(layers "F.Cu" "F.Mask" "F.Paste")
			(net "GND")
		)
		(pad "BH23" smd circle
			(at -1.89992 21.850096)
			(size 0.4572 0.4572)
			(layers "F.Cu" "F.Mask" "F.Paste")
			(net "P5E_PEX1_STN2_RX_DP<33>")
		)
		(pad "BH24" smd circle
			(at -0.94996 21.850096)
			(size 0.4572 0.4572)
			(layers "F.Cu" "F.Mask" "F.Paste")
			(net "GND")
		)
		(pad "BH25" smd circle
			(at 0 21.850096)
			(size 0.4572 0.4572)
			(layers "F.Cu" "F.Mask" "F.Paste")
			(net "P5E_PEX1_STN1_RX_DP<16>")
		)
		(pad "BH26" smd circle
			(at 0.94996 21.850096)
			(size 0.4572 0.4572)
			(layers "F.Cu" "F.Mask" "F.Paste")
			(net "GND")
		)
		(pad "BH27" smd circle
			(at 1.89992 21.850096)
			(size 0.4572 0.4572)
			(layers "F.Cu" "F.Mask" "F.Paste")
			(net "P5E_PEX1_STN1_RX_DP<18>")
		)
		(pad "BH28" smd circle
			(at 2.84988 21.850096)
			(size 0.4572 0.4572)
			(layers "F.Cu" "F.Mask" "F.Paste")
			(net "GND")
		)
		(pad "BH29" smd circle
			(at 3.800094 21.850096)
			(size 0.4572 0.4572)
			(layers "F.Cu" "F.Mask" "F.Paste")
			(net "P5E_PEX1_STN1_RX_DP<20>")
		)
		(pad "BH30" smd circle
			(at 4.750054 21.850096)
			(size 0.4572 0.4572)
			(layers "F.Cu" "F.Mask" "F.Paste")
			(net "GND")
		)
		(pad "BH31" smd circle
			(at 5.700014 21.850096)
			(size 0.4572 0.4572)
			(layers "F.Cu" "F.Mask" "F.Paste")
			(net "P5E_PEX1_STN1_RX_DP<22>")
		)
		(pad "BH32" smd circle
			(at 6.649974 21.850096)
			(size 0.4572 0.4572)
			(layers "F.Cu" "F.Mask" "F.Paste")
			(net "GND")
		)
		(pad "BH33" smd circle
			(at 7.599934 21.850096)
			(size 0.4572 0.4572)
			(layers "F.Cu" "F.Mask" "F.Paste")
			(net "P5E_PEX1_STN1_RX_DP<24>")
		)
		(pad "BH34" smd circle
			(at 8.549894 21.850096)
			(size 0.4572 0.4572)
			(layers "F.Cu" "F.Mask" "F.Paste")
			(net "GND")
		)
		(pad "BH35" smd circle
			(at 9.500108 21.850096)
			(size 0.4572 0.4572)
			(layers "F.Cu" "F.Mask" "F.Paste")
			(net "P5E_PEX1_STN1_RX_DP<26>")
		)
		(pad "BH36" smd circle
			(at 10.450068 21.850096)
			(size 0.4572 0.4572)
			(layers "F.Cu" "F.Mask" "F.Paste")
			(net "GND")
		)
		(pad "BH37" smd circle
			(at 11.400028 21.850096)
			(size 0.4572 0.4572)
			(layers "F.Cu" "F.Mask" "F.Paste")
			(net "P5E_PEX1_STN1_RX_DP<28>")
		)
		(pad "BH38" smd circle
			(at 12.349988 21.850096)
			(size 0.4572 0.4572)
			(layers "F.Cu" "F.Mask" "F.Paste")
			(net "GND")
		)
		(pad "BH39" smd circle
			(at 13.299948 21.850096)
			(size 0.4572 0.4572)
			(layers "F.Cu" "F.Mask" "F.Paste")
			(net "P5E_PEX1_STN1_RX_DP<30>")
		)
		(pad "BH40" smd circle
			(at 14.249908 21.850096)
			(size 0.4572 0.4572)
			(layers "F.Cu" "F.Mask" "F.Paste")
			(net "GND")
		)
		(pad "BH41" smd circle
			(at 15.200122 21.850096)
			(size 0.4572 0.4572)
			(layers "F.Cu" "F.Mask" "F.Paste")
			(net "P5E_PEX1_STN0_RX_DP<15>")
		)
		(pad "BH42" smd circle
			(at 16.150082 21.850096)
			(size 0.4572 0.4572)
			(layers "F.Cu" "F.Mask" "F.Paste")
			(net "GND")
		)
		(pad "BH43" smd circle
			(at 17.100042 21.850096)
			(size 0.4572 0.4572)
			(layers "F.Cu" "F.Mask" "F.Paste")
			(net "P5E_PEX1_STN0_RX_DP<13>")
		)
		(pad "BH44" smd circle
			(at 18.050002 21.850096)
			(size 0.4572 0.4572)
			(layers "F.Cu" "F.Mask" "F.Paste")
			(net "GND")
		)
		(pad "BH45" smd circle
			(at 18.999962 21.850096)
			(size 0.4572 0.4572)
			(layers "F.Cu" "F.Mask" "F.Paste")
			(net "P5E_PEX1_STN0_RX_DP<11>")
		)
		(pad "BH46" smd circle
			(at 19.949922 21.850096)
			(size 0.4572 0.4572)
			(layers "F.Cu" "F.Mask" "F.Paste")
			(net "GND")
		)
		(pad "BH47" smd circle
			(at 20.899882 21.850096)
			(size 0.4572 0.4572)
			(layers "F.Cu" "F.Mask" "F.Paste")
			(net "P5E_PEX1_STN0_RX_DP<9>")
		)
		(pad "BH48" smd circle
			(at 21.850096 21.850096)
			(size 0.4572 0.4572)
			(layers "F.Cu" "F.Mask" "F.Paste")
			(net "GND")
		)
		(pad "BH49" smd circle
			(at 22.800056 21.850096)
			(size 0.4572 0.4572)
			(layers "F.Cu" "F.Mask" "F.Paste")
			(net "GND")
		)
		(pad "BJ2" smd circle
			(at -21.850096 22.800056)
			(size 0.4572 0.4572)
			(layers "F.Cu" "F.Mask" "F.Paste")
			(net "GND")
		)
		(pad "BJ3" smd circle
			(at -20.899882 22.800056)
			(size 0.4572 0.4572)
			(layers "F.Cu" "F.Mask" "F.Paste")
			(net "Net_1380")
		)
		(pad "BJ4" smd circle
			(at -19.949922 22.800056)
			(size 0.4572 0.4572)
			(layers "F.Cu" "F.Mask" "F.Paste")
			(net "GND")
		)
		(pad "BJ5" smd circle
			(at -18.999962 22.800056)
			(size 0.4572 0.4572)
			(layers "F.Cu" "F.Mask" "F.Paste")
			(net "Net_1723")
		)
		(pad "BJ6" smd circle
			(at -18.050002 22.800056)
			(size 0.4572 0.4572)
			(layers "F.Cu" "F.Mask" "F.Paste")
			(net "GND")
		)
		(pad "BJ7" smd circle
			(at -17.100042 22.800056)
			(size 0.4572 0.4572)
			(layers "F.Cu" "F.Mask" "F.Paste")
			(net "Net_1418")
		)
		(pad "BJ8" smd circle
			(at -16.150082 22.800056)
			(size 0.4572 0.4572)
			(layers "F.Cu" "F.Mask" "F.Paste")
			(net "GND")
		)
		(pad "BJ9" smd circle
			(at -15.200122 22.800056)
			(size 0.4572 0.4572)
			(layers "F.Cu" "F.Mask" "F.Paste")
			(net "P5E_PEX1_STN2_RX_DN<47>")
		)
		(pad "BJ10" smd circle
			(at -14.249908 22.800056)
			(size 0.4572 0.4572)
			(layers "F.Cu" "F.Mask" "F.Paste")
			(net "GND")
		)
		(pad "BJ11" smd circle
			(at -13.299948 22.800056)
			(size 0.4572 0.4572)
			(layers "F.Cu" "F.Mask" "F.Paste")
			(net "P5E_PEX1_STN2_RX_DN<45>")
		)
		(pad "BJ12" smd circle
			(at -12.349988 22.800056)
			(size 0.4572 0.4572)
			(layers "F.Cu" "F.Mask" "F.Paste")
			(net "GND")
		)
		(pad "BJ13" smd circle
			(at -11.400028 22.800056)
			(size 0.4572 0.4572)
			(layers "F.Cu" "F.Mask" "F.Paste")
			(net "P5E_PEX1_STN2_RX_DN<43>")
		)
		(pad "BJ14" smd circle
			(at -10.450068 22.800056)
			(size 0.4572 0.4572)
			(layers "F.Cu" "F.Mask" "F.Paste")
			(net "GND")
		)
		(pad "BJ15" smd circle
			(at -9.500108 22.800056)
			(size 0.4572 0.4572)
			(layers "F.Cu" "F.Mask" "F.Paste")
			(net "P5E_PEX1_STN2_RX_DN<41>")
		)
		(pad "BJ16" smd circle
			(at -8.549894 22.800056)
			(size 0.4572 0.4572)
			(layers "F.Cu" "F.Mask" "F.Paste")
			(net "GND")
		)
		(pad "BJ17" smd circle
			(at -7.599934 22.800056)
			(size 0.4572 0.4572)
			(layers "F.Cu" "F.Mask" "F.Paste")
			(net "P5E_PEX1_STN2_RX_DN<39>")
		)
		(pad "BJ18" smd circle
			(at -6.649974 22.800056)
			(size 0.4572 0.4572)
			(layers "F.Cu" "F.Mask" "F.Paste")
			(net "GND")
		)
		(pad "BJ19" smd circle
			(at -5.700014 22.800056)
			(size 0.4572 0.4572)
			(layers "F.Cu" "F.Mask" "F.Paste")
			(net "P5E_PEX1_STN2_RX_DN<37>")
		)
		(pad "BJ20" smd circle
			(at -4.750054 22.800056)
			(size 0.4572 0.4572)
			(layers "F.Cu" "F.Mask" "F.Paste")
			(net "GND")
		)
		(pad "BJ21" smd circle
			(at -3.800094 22.800056)
			(size 0.4572 0.4572)
			(layers "F.Cu" "F.Mask" "F.Paste")
			(net "P5E_PEX1_STN2_RX_DN<35>")
		)
		(pad "BJ22" smd circle
			(at -2.84988 22.800056)
			(size 0.4572 0.4572)
			(layers "F.Cu" "F.Mask" "F.Paste")
			(net "GND")
		)
		(pad "BJ23" smd circle
			(at -1.89992 22.800056)
			(size 0.4572 0.4572)
			(layers "F.Cu" "F.Mask" "F.Paste")
			(net "P5E_PEX1_STN2_RX_DN<33>")
		)
		(pad "BJ24" smd circle
			(at -0.94996 22.800056)
			(size 0.4572 0.4572)
			(layers "F.Cu" "F.Mask" "F.Paste")
			(net "GND")
		)
		(pad "BJ25" smd circle
			(at 0 22.800056)
			(size 0.4572 0.4572)
			(layers "F.Cu" "F.Mask" "F.Paste")
			(net "P5E_PEX1_STN1_RX_DN<16>")
		)
		(pad "BJ26" smd circle
			(at 0.94996 22.800056)
			(size 0.4572 0.4572)
			(layers "F.Cu" "F.Mask" "F.Paste")
			(net "GND")
		)
		(pad "BJ27" smd circle
			(at 1.89992 22.800056)
			(size 0.4572 0.4572)
			(layers "F.Cu" "F.Mask" "F.Paste")
			(net "P5E_PEX1_STN1_RX_DN<18>")
		)
		(pad "BJ28" smd circle
			(at 2.84988 22.800056)
			(size 0.4572 0.4572)
			(layers "F.Cu" "F.Mask" "F.Paste")
			(net "GND")
		)
		(pad "BJ29" smd circle
			(at 3.800094 22.800056)
			(size 0.4572 0.4572)
			(layers "F.Cu" "F.Mask" "F.Paste")
			(net "P5E_PEX1_STN1_RX_DN<20>")
		)
		(pad "BJ30" smd circle
			(at 4.750054 22.800056)
			(size 0.4572 0.4572)
			(layers "F.Cu" "F.Mask" "F.Paste")
			(net "GND")
		)
		(pad "BJ31" smd circle
			(at 5.700014 22.800056)
			(size 0.4572 0.4572)
			(layers "F.Cu" "F.Mask" "F.Paste")
			(net "P5E_PEX1_STN1_RX_DN<22>")
		)
		(pad "BJ32" smd circle
			(at 6.649974 22.800056)
			(size 0.4572 0.4572)
			(layers "F.Cu" "F.Mask" "F.Paste")
			(net "GND")
		)
		(pad "BJ33" smd circle
			(at 7.599934 22.800056)
			(size 0.4572 0.4572)
			(layers "F.Cu" "F.Mask" "F.Paste")
			(net "P5E_PEX1_STN1_RX_DN<24>")
		)
		(pad "BJ34" smd circle
			(at 8.549894 22.800056)
			(size 0.4572 0.4572)
			(layers "F.Cu" "F.Mask" "F.Paste")
			(net "GND")
		)
		(pad "BJ35" smd circle
			(at 9.500108 22.800056)
			(size 0.4572 0.4572)
			(layers "F.Cu" "F.Mask" "F.Paste")
			(net "P5E_PEX1_STN1_RX_DN<26>")
		)
		(pad "BJ36" smd circle
			(at 10.450068 22.800056)
			(size 0.4572 0.4572)
			(layers "F.Cu" "F.Mask" "F.Paste")
			(net "GND")
		)
		(pad "BJ37" smd circle
			(at 11.400028 22.800056)
			(size 0.4572 0.4572)
			(layers "F.Cu" "F.Mask" "F.Paste")
			(net "P5E_PEX1_STN1_RX_DN<28>")
		)
		(pad "BJ38" smd circle
			(at 12.349988 22.800056)
			(size 0.4572 0.4572)
			(layers "F.Cu" "F.Mask" "F.Paste")
			(net "GND")
		)
		(pad "BJ39" smd circle
			(at 13.299948 22.800056)
			(size 0.4572 0.4572)
			(layers "F.Cu" "F.Mask" "F.Paste")
			(net "P5E_PEX1_STN1_RX_DN<30>")
		)
		(pad "BJ40" smd circle
			(at 14.249908 22.800056)
			(size 0.4572 0.4572)
			(layers "F.Cu" "F.Mask" "F.Paste")
			(net "GND")
		)
		(pad "BJ41" smd circle
			(at 15.200122 22.800056)
			(size 0.4572 0.4572)
			(layers "F.Cu" "F.Mask" "F.Paste")
			(net "P5E_PEX1_STN0_RX_DN<15>")
		)
		(pad "BJ42" smd circle
			(at 16.150082 22.800056)
			(size 0.4572 0.4572)
			(layers "F.Cu" "F.Mask" "F.Paste")
			(net "GND")
		)
		(pad "BJ43" smd circle
			(at 17.100042 22.800056)
			(size 0.4572 0.4572)
			(layers "F.Cu" "F.Mask" "F.Paste")
			(net "P5E_PEX1_STN0_RX_DN<13>")
		)
		(pad "BJ44" smd circle
			(at 18.050002 22.800056)
			(size 0.4572 0.4572)
			(layers "F.Cu" "F.Mask" "F.Paste")
			(net "GND")
		)
		(pad "BJ45" smd circle
			(at 18.999962 22.800056)
			(size 0.4572 0.4572)
			(layers "F.Cu" "F.Mask" "F.Paste")
			(net "P5E_PEX1_STN0_RX_DN<11>")
		)
		(pad "BJ46" smd circle
			(at 19.949922 22.800056)
			(size 0.4572 0.4572)
			(layers "F.Cu" "F.Mask" "F.Paste")
			(net "GND")
		)
		(pad "BJ47" smd circle
			(at 20.899882 22.800056)
			(size 0.4572 0.4572)
			(layers "F.Cu" "F.Mask" "F.Paste")
			(net "P5E_PEX1_STN0_RX_DN<9>")
		)
		(pad "BJ48" smd circle
			(at 21.850096 22.800056)
			(size 0.4572 0.4572)
			(layers "F.Cu" "F.Mask" "F.Paste")
			(net "GND")
		)
		(pad "C1" smd circle
			(at -22.800056 -20.899882)
			(size 0.4572 0.4572)
			(layers "F.Cu" "F.Mask" "F.Paste")
			(net "P5E_PEX1_STN7_RX_DN<122>")
		)
		(pad "C2" smd circle
			(at -21.850096 -20.899882)
			(size 0.4572 0.4572)
			(layers "F.Cu" "F.Mask" "F.Paste")
			(net "P5E_PEX1_STN7_RX_DP<122>")
		)
		(pad "C3" smd circle
			(at -20.899882 -20.899882)
			(size 0.4572 0.4572)
			(layers "F.Cu" "F.Mask" "F.Paste")
			(net "GND")
		)
		(pad "C4" smd circle
			(at -19.949922 -20.899882)
			(size 0.4572 0.4572)
			(layers "F.Cu" "F.Mask" "F.Paste")
			(net "P5E_PEX1_STN7_RX_DN<124>")
		)
		(pad "C5" smd circle
			(at -18.999962 -20.899882)
			(size 0.4572 0.4572)
			(layers "F.Cu" "F.Mask" "F.Paste")
			(net "GND")
		)
		(pad "C6" smd circle
			(at -18.050002 -20.899882)
			(size 0.4572 0.4572)
			(layers "F.Cu" "F.Mask" "F.Paste")
			(net "P5E_PEX1_STN7_RX_DN<126>")
		)
		(pad "C7" smd circle
			(at -17.100042 -20.899882)
			(size 0.4572 0.4572)
			(layers "F.Cu" "F.Mask" "F.Paste")
			(net "GND")
		)
		(pad "C8" smd circle
			(at -16.150082 -20.899882)
			(size 0.4572 0.4572)
			(layers "F.Cu" "F.Mask" "F.Paste")
			(net "P5E_PEX1_STN6_RX_DN<111>")
		)
		(pad "C9" smd circle
			(at -15.200122 -20.899882)
			(size 0.4572 0.4572)
			(layers "F.Cu" "F.Mask" "F.Paste")
			(net "GND")
		)
		(pad "C10" smd circle
			(at -14.249908 -20.899882)
			(size 0.4572 0.4572)
			(layers "F.Cu" "F.Mask" "F.Paste")
			(net "P5E_PEX1_STN6_RX_DN<109>")
		)
		(pad "C11" smd circle
			(at -13.299948 -20.899882)
			(size 0.4572 0.4572)
			(layers "F.Cu" "F.Mask" "F.Paste")
			(net "GND")
		)
		(pad "C12" smd circle
			(at -12.349988 -20.899882)
			(size 0.4572 0.4572)
			(layers "F.Cu" "F.Mask" "F.Paste")
			(net "P5E_PEX1_STN6_RX_DN<107>")
		)
		(pad "C13" smd circle
			(at -11.400028 -20.899882)
			(size 0.4572 0.4572)
			(layers "F.Cu" "F.Mask" "F.Paste")
			(net "GND")
		)
		(pad "C14" smd circle
			(at -10.450068 -20.899882)
			(size 0.4572 0.4572)
			(layers "F.Cu" "F.Mask" "F.Paste")
			(net "P5E_PEX1_STN6_RX_DN<105>")
		)
		(pad "C15" smd circle
			(at -9.500108 -20.899882)
			(size 0.4572 0.4572)
			(layers "F.Cu" "F.Mask" "F.Paste")
			(net "GND")
		)
		(pad "C16" smd circle
			(at -8.549894 -20.899882)
			(size 0.4572 0.4572)
			(layers "F.Cu" "F.Mask" "F.Paste")
			(net "P5E_PEX1_STN6_RX_DN<103>")
		)
		(pad "C17" smd circle
			(at -7.599934 -20.899882)
			(size 0.4572 0.4572)
			(layers "F.Cu" "F.Mask" "F.Paste")
			(net "GND")
		)
		(pad "C18" smd circle
			(at -6.649974 -20.899882)
			(size 0.4572 0.4572)
			(layers "F.Cu" "F.Mask" "F.Paste")
			(net "P5E_PEX1_STN6_RX_DN<101>")
		)
		(pad "C19" smd circle
			(at -5.700014 -20.899882)
			(size 0.4572 0.4572)
			(layers "F.Cu" "F.Mask" "F.Paste")
			(net "GND")
		)
		(pad "C20" smd circle
			(at -4.750054 -20.899882)
			(size 0.4572 0.4572)
			(layers "F.Cu" "F.Mask" "F.Paste")
			(net "P5E_PEX1_STN6_RX_DN<99>")
		)
		(pad "C21" smd circle
			(at -3.800094 -20.899882)
			(size 0.4572 0.4572)
			(layers "F.Cu" "F.Mask" "F.Paste")
			(net "GND")
		)
	)
)
